# T6G (Grand Teton) — schematic netlist excerpt (pin names and nets, part order shuffled) for the footprints in the layout excerpt that follows; sources: Cadence DE-HDL packaged netlist, KiCad conversion of 04192023_DAF0TMB3IC0_F0TG_MB_C_brd_V02_OCP.brd

PC614_3  Q_CAP  22UF 4V 20% X6S  pkg C0805  page 199 : A = PVDDCR_SOC_P0 ; B = GND
PR375  Q_RES  0 5% CHIP  pkg 0402LF  page 223 : A = PVDDIO_P1_VOS4 ; B = PVDDIO_P1
C2210  Q_CAP  22UF 4V 20% X6S  pkg C0402  page 69 : A = PVDDCR_CPU1_P0 ; B = GND

(kicad_pcb
	(version 20260206)
	(generator "pcbnew")
	(generator_version "10.0")
	(general
		(thickness 1.6)
		(legacy_teardrops no)
	)
	(paper "A4")
	(title_block
		(title "04192023_DAF0TMB3IC0_F0TG_MB_C_brd_V02_OCP.brd")
		(comment 1 "Grand Teton / footprints 5107-5109 of 8354")
	)
	(layers
		(0 "F.Cu" signal "TOP")
		(4 "In1.Cu" signal "GND")
		(6 "In2.Cu" signal "IN1")
		(8 "In3.Cu" signal "GND1")
		(10 "In4.Cu" signal "IN2")
		(12 "In5.Cu" signal "GND2")
		(14 "In6.Cu" signal "IN3")
		(16 "In7.Cu" signal "GND3")
		(18 "In8.Cu" signal "VCC")
		(20 "In9.Cu" signal "VCC1")
		(22 "In10.Cu" signal "GND4")
		(24 "In11.Cu" signal "IN4")
		(26 "In12.Cu" signal "GND5")
		(28 "In13.Cu" signal "IN5")
		(30 "In14.Cu" signal "GND6")
		(32 "In15.Cu" signal "IN6")
		(34 "In16.Cu" signal "GND7")
		(2 "B.Cu" signal "BOTTOM")
		(9 "F.Adhes" user "F.Adhesive")
		(11 "B.Adhes" user "B.Adhesive")
		(13 "F.Paste" user "Package Geometry/Pastemask Top")
		(15 "B.Paste" user "Package Geometry/Pastemask Bottom")
		(5 "F.SilkS" user "Ref Des/Silkscreen Top")
		(7 "B.SilkS" user "Ref Des/Silkscreen Bottom")
		(1 "F.Mask" user "Board Geometry/Soldermask Top")
		(3 "B.Mask" user "Board Geometry/Soldermask Bottom")
		(17 "Dwgs.User" user "User.Drawings")
		(19 "Cmts.User" user "User.Comments")
		(21 "Eco1.User" user "User.Eco1")
		(23 "Eco2.User" user "User.Eco2")
		(25 "Edge.Cuts" user "Board Geometry/Outline")
		(27 "Margin" user)
		(31 "F.CrtYd" user "Package Geometry/Place Bound Top")
		(29 "B.CrtYd" user "Package Geometry/Place Bound Bottom")
		(35 "F.Fab" user "Ref Des/Assembly Top")
		(33 "B.Fab" user "Ref Des/Assembly Bottom")
	)
	(footprint ""
		(layer "B.Cu")
		(at 350.723454 -269.30731)
		(property "Reference" "C2210"
			(at 0 0 0)
			(layer "B.SilkS")
			(hide yes)
			(effects
				(font
					(size 1.27 1.27)
				)
				(justify mirror)
			)
		)
		(property "Value" ""
			(at 0 0 0)
			(layer "B.Fab")
			(effects
				(font
					(size 1.27 1.27)
				)
				(justify mirror)
			)
		)
		(duplicate_pad_numbers_are_jumpers no)
		(fp_line
			(start -0.7874 -0.4064)
			(end -0.7874 0.4064)
			(stroke
				(width 0.1524)
				(type default)
			)
			(layer "B.SilkS")
		)
		(fp_line
			(start -0.7874 0.4064)
			(end 0.7874 0.4064)
			(stroke
				(width 0.1524)
				(type default)
			)
			(layer "B.SilkS")
		)
		(fp_line
			(start 0.7874 -0.4064)
			(end -0.7874 -0.4064)
			(stroke
				(width 0.1524)
				(type default)
			)
			(layer "B.SilkS")
		)
		(fp_line
			(start 0.7874 0.4064)
			(end 0.7874 -0.4064)
			(stroke
				(width 0.1524)
				(type default)
			)
			(layer "B.SilkS")
		)
		(fp_line
			(start -0.67945 -0.3048)
			(end -0.67945 0.3048)
			(stroke
				(width 0.1)
				(type default)
			)
			(layer "B.Fab")
		)
		(fp_line
			(start -0.67945 0.3048)
			(end -0.120396 0.3048)
			(stroke
				(width 0.1)
				(type default)
			)
			(layer "B.Fab")
		)
		(fp_line
			(start -0.12065 -0.3048)
			(end -0.67945 -0.3048)
			(stroke
				(width 0.1)
				(type default)
			)
			(layer "B.Fab")
		)
		(fp_line
			(start -0.12065 -0.2794)
			(end -0.12065 -0.3048)
			(stroke
				(width 0.1)
				(type default)
			)
			(layer "B.Fab")
		)
		(fp_line
			(start -0.120396 0.2794)
			(end 0.12065 0.2794)
			(stroke
				(width 0.1)
				(type default)
			)
			(layer "B.Fab")
		)
		(fp_line
			(start -0.120396 0.3048)
			(end -0.120396 0.2794)
			(stroke
				(width 0.1)
				(type default)
			)
			(layer "B.Fab")
		)
		(fp_line
			(start 0.12065 -0.305054)
			(end 0.12065 -0.2794)
			(stroke
				(width 0.1)
				(type default)
			)
			(layer "B.Fab")
		)
		(fp_line
			(start 0.12065 -0.2794)
			(end -0.12065 -0.2794)
			(stroke
				(width 0.1)
				(type default)
			)
			(layer "B.Fab")
		)
		(fp_line
			(start 0.12065 0.2794)
			(end 0.12065 0.3048)
			(stroke
				(width 0.1)
				(type default)
			)
			(layer "B.Fab")
		)
		(fp_line
			(start 0.12065 0.3048)
			(end 0.67945 0.3048)
			(stroke
				(width 0.1)
				(type default)
			)
			(layer "B.Fab")
		)
		(fp_line
			(start 0.67945 -0.305054)
			(end 0.12065 -0.305054)
			(stroke
				(width 0.1)
				(type default)
			)
			(layer "B.Fab")
		)
		(fp_line
			(start 0.67945 0.3048)
			(end 0.67945 -0.305054)
			(stroke
				(width 0.1)
				(type default)
			)
			(layer "B.Fab")
		)
		(pad "1" smd circle
			(at 0.40005 0 180)
			(size 0 0)
			(layers "B.Cu" "B.Mask" "B.Paste")
			(net "PVDDCR_CPU1_P0")
		)
		(pad "2" smd circle
			(at -0.40005 0 180)
			(size 0 0)
			(layers "B.Cu" "B.Mask" "B.Paste")
			(net "GND")
		)
	)
	(footprint ""
		(layer "B.Cu")
		(at 24.939244 -349.386398 -90)
		(property "Reference" "PR375"
			(at 0 0 90)
			(layer "B.SilkS")
			(hide yes)
			(effects
				(font
					(size 1.27 1.27)
				)
				(justify mirror)
			)
		)
		(property "Value" ""
			(at 0 0 90)
			(layer "B.Fab")
			(effects
				(font
					(size 1.27 1.27)
				)
				(justify mirror)
			)
		)
		(duplicate_pad_numbers_are_jumpers no)
		(fp_line
			(start -0.7874 0.4064)
			(end 0.7874 0.4064)
			(stroke
				(width 0.1524)
				(type default)
			)
			(layer "B.SilkS")
		)
		(fp_line
			(start 0.7874 0.4064)
			(end 0.7874 -0.4064)
			(stroke
				(width 0.1524)
				(type default)
			)
			(layer "B.SilkS")
		)
		(fp_line
			(start -0.7874 -0.4064)
			(end -0.7874 0.4064)
			(stroke
				(width 0.1524)
				(type default)
			)
			(layer "B.SilkS")
		)
		(fp_line
			(start 0.7874 -0.4064)
			(end -0.7874 -0.4064)
			(stroke
				(width 0.1524)
				(type default)
			)
			(layer "B.SilkS")
		)
		(fp_line
			(start -0.67945 0.3048)
			(end -0.120396 0.3048)
			(stroke
				(width 0.1)
				(type default)
			)
			(layer "B.Fab")
		)
		(fp_line
			(start -0.120396 0.3048)
			(end -0.120396 0.2794)
			(stroke
				(width 0.1)
				(type default)
			)
			(layer "B.Fab")
		)
		(fp_line
			(start 0.12065 0.3048)
			(end 0.67945 0.3048)
			(stroke
				(width 0.1)
				(type default)
			)
			(layer "B.Fab")
		)
		(fp_line
			(start 0.67945 0.3048)
			(end 0.67945 -0.305054)
			(stroke
				(width 0.1)
				(type default)
			)
			(layer "B.Fab")
		)
		(fp_line
			(start -0.120396 0.2794)
			(end 0.12065 0.2794)
			(stroke
				(width 0.1)
				(type default)
			)
			(layer "B.Fab")
		)
		(fp_line
			(start 0.12065 0.2794)
			(end 0.12065 0.3048)
			(stroke
				(width 0.1)
				(type default)
			)
			(layer "B.Fab")
		)
		(fp_line
			(start -0.12065 -0.2794)
			(end -0.12065 -0.3048)
			(stroke
				(width 0.1)
				(type default)
			)
			(layer "B.Fab")
		)
		(fp_line
			(start 0.12065 -0.2794)
			(end -0.12065 -0.2794)
			(stroke
				(width 0.1)
				(type default)
			)
			(layer "B.Fab")
		)
		(fp_line
			(start -0.67945 -0.3048)
			(end -0.67945 0.3048)
			(stroke
				(width 0.1)
				(type default)
			)
			(layer "B.Fab")
		)
		(fp_line
			(start -0.12065 -0.3048)
			(end -0.67945 -0.3048)
			(stroke
				(width 0.1)
				(type default)
			)
			(layer "B.Fab")
		)
		(fp_line
			(start 0.12065 -0.305054)
			(end 0.12065 -0.2794)
			(stroke
				(width 0.1)
				(type default)
			)
			(layer "B.Fab")
		)
		(fp_line
			(start 0.67945 -0.305054)
			(end 0.12065 -0.305054)
			(stroke
				(width 0.1)
				(type default)
			)
			(layer "B.Fab")
		)
		(pad "1" smd circle
			(at 0.40005 0 90)
			(size 0 0)
			(layers "B.Cu" "B.Mask" "B.Paste")
			(net "PVDDIO_P1_VOS4")
		)
		(pad "2" smd circle
			(at -0.40005 0 90)
			(size 0 0)
			(layers "B.Cu" "B.Mask" "B.Paste")
			(net "PVDDIO_P1")
		)
	)
	(footprint ""
		(layer "B.Cu")
		(at 412.0642 -172.407072 90)
		(property "Reference" "PC614_3"
			(at 0 0 90)
			(layer "B.SilkS")
			(hide yes)
			(effects
				(font
					(size 1.27 1.27)
				)
				(justify mirror)
			)
		)
		(property "Value" ""
			(at 0 0 90)
			(layer "B.Fab")
			(effects
				(font
					(size 1.27 1.27)
				)
				(justify mirror)
			)
		)
		(duplicate_pad_numbers_are_jumpers no)
		(fp_line
			(start 1.524 -0.762)
			(end -1.524 -0.762)
			(stroke
				(width 0.1524)
				(type default)
			)
			(layer "B.SilkS")
		)
		(fp_line
			(start -1.524 -0.762)
			(end -1.524 0.762)
			(stroke
				(width 0.1524)
				(type default)
			)
			(layer "B.SilkS")
		)
		(fp_line
			(start 1.524 0.762)
			(end 1.524 -0.762)
			(stroke
				(width 0.1524)
				(type default)
			)
			(layer "B.SilkS")
		)
		(fp_line
			(start -1.524 0.762)
			(end 1.524 0.762)
			(stroke
				(width 0.1524)
				(type default)
			)
			(layer "B.SilkS")
		)
		(fp_line
			(start 1.1049 -0.724916)
			(end 1.1049 0.724916)
			(stroke
				(width 0.1)
				(type default)
			)
			(layer "B.Fab")
		)
		(fp_line
			(start -1.1049 -0.724916)
			(end 1.1049 -0.724916)
			(stroke
				(width 0.1)
				(type default)
			)
			(layer "B.Fab")
		)
		(fp_line
			(start 1.1049 0.724916)
			(end -1.1049 0.724916)
			(stroke
				(width 0.1)
				(type default)
			)
			(layer "B.Fab")
		)
		(fp_line
			(start -1.1049 0.724916)
			(end -1.1049 -0.724916)
			(stroke
				(width 0.1)
				(type default)
			)
			(layer "B.Fab")
		)
		(pad "1" smd rect
			(at 0.889 0 90)
			(size 1.016 1.27)
			(layers "B.Cu" "B.Mask" "B.Paste")
			(net "PVDDCR_SOC_P0")
		)
		(pad "2" smd rect
			(at -0.889 0 90)
			(size 1.016 1.27)
			(layers "B.Cu" "B.Mask" "B.Paste")
			(net "GND")
		)
	)
)
